# T6G (Grand Teton) — schematic netlist excerpt (pin names and nets, part order shuffled) for the footprints in the layout excerpt that follows; sources: Cadence DE-HDL packaged netlist, KiCad conversion of 04192023_DAF0TMB3IC0_F0TG_MB_C_brd_V02_OCP.brd

J30  SCONN288_DDR506112002KQ  IO  pkg DDR288S_1-1VXC  page 101
  VIN_BULK0  = P12V_MEM_CPU1
  RFU0  = NC
  VIN_MGMT  = P3V3_AUX
  HSCL  = I3C_SPD_DDRD_CPU1_SCL
  HSDA  = I3C_SPD_DDRD_CPU1_SDA
  VSS0  = GND
  DQ0_A  = M_D_CPU1_SA_DQ<0>
  VSS1  = GND
  DQ1_A  = M_D_CPU1_SA_DQ<1>
  VSS2  = GND
  DQS0_A_T  = M_D_CPU1_SA_DQS_DP<0>
  DQS0_A_C  = M_D_CPU1_SA_DQS_DN<0>
  VSS3  = GND
  DQ4_A  = M_D_CPU1_SA_DQ<4>
  VSS4  = GND
  DQ5_A  = M_D_CPU1_SA_DQ<5>
  VSS5  = GND
  DQ8_A  = M_D_CPU1_SA_DQ<8>
  VSS6  = GND
  DQ9_A  = M_D_CPU1_SA_DQ<9>
  VSS7  = GND
  DQS1_A_T  = M_D_CPU1_SA_DQS_DP<1>
  DQS1_A_C  = M_D_CPU1_SA_DQS_DN<1>
  VSS8  = GND
  DQ12_A  = M_D_CPU1_SA_DQ<12>
  VSS9  = GND
  DQ13_A  = M_D_CPU1_SA_DQ<13>
  VSS10  = GND
  DQ16_A  = M_D_CPU1_SA_DQ<16>
  VSS11  = GND
  DQ17_A  = M_D_CPU1_SA_DQ<17>
  VSS12  = GND
  DQS2_A_T  = M_D_CPU1_SA_DQS_DP<2>
  DQS2_A_C  = M_D_CPU1_SA_DQS_DN<2>
  VSS13  = GND
  DQ20_A  = M_D_CPU1_SA_DQ<20>
  VSS14  = GND
  DQ21_A  = M_D_CPU1_SA_DQ<21>
  VSS15  = GND
  DQ24_A  = M_D_CPU1_SA_DQ<24>
  VSS16  = GND
  DQ25_A  = M_D_CPU1_SA_DQ<25>
  VSS17  = GND
  DQS3_A_T  = M_D_CPU1_SA_DQS_DP<3>
  DQS3_A_C  = M_D_CPU1_SA_DQS_DN<3>
  VSS18  = GND
  DQ28_A  = M_D_CPU1_SA_DQ<28>
  VSS19  = GND
  DQ29_A  = M_D_CPU1_SA_DQ<29>
  VSS20  = GND
  CB0_A  = M_D_CPU1_SA_CB<0>
  VSS21  = GND
  CB1_A  = M_D_CPU1_SA_CB<1>
  VSS22  = GND
  DQS4_A_T  = M_D_CPU1_SA_DQS_DP<4>
  DQS4_A_C  = M_D_CPU1_SA_DQS_DN<4>
  VSS23  = GND
  CB4_A  = M_D_CPU1_SA_CB<4>
  VSS24  = GND
  CB5_A  = M_D_CPU1_SA_CB<5>
  VSS25  = GND
  ALERT_N  = M_D_CPU1_ALERT_N
  VSS26  = GND
  CS0_A_N  = M_D_CPU1_SA_CS_N<0>
  VSS27  = GND
  CA0_A  = M_D_CPU1_SA_CA<0>
  VSS28  = GND
  CA2_A  = M_D_CPU1_SA_CA<2>
  VSS29  = GND
  CA4_A  = M_D_CPU1_SA_CA<4>
  VSS30  = GND
  CA6_A  = M_D_CPU1_SA_CA<6>
  VSS31  = GND
  PAR_A  = M_D_CPU1_SA_PAR
  VSS32  = GND
  CA0_B  = M_D_CPU1_SB_CA<0>
  VSS33  = GND
  CA2_B  = M_D_CPU1_SB_CA<2>
  VSS34  = GND
  CA4_B  = M_D_CPU1_SB_CA<4>
  VSS35  = GND
  CA6_B  = M_D_CPU1_SB_CA<6>
  VSS36  = GND
  CS0_B_N  = M_D_CPU1_SB_CS_N<0>
  VSS37  = GND
  \lbd||rsp_a_n\  = M_D_CPU1_SA_RSP<0>
  \lbs||rsp_b_n\  = M_D_CPU1_SB_RSP<0>
  VSS38  = GND
  CB4_B  = M_D_CPU1_SB_CB<4>
  VSS39  = GND
  CB5_B  = M_D_CPU1_SB_CB<5>
  VSS40  = GND
  \dqs9_b_t||tdqs9_b_t||dbi4_b_n\  = M_D_CPU1_SB_DQS_DP<9>
  \dqs9_b_c||tdqs9_b_c\  = M_D_CPU1_SB_DQS_DN<9>
  VSS41  = GND
  CB0_B  = M_D_CPU1_SB_CB<0>
  VSS42  = GND
  CB1_B  = M_D_CPU1_SB_CB<1>
  VSS43  = GND
  DQ0_B  = M_D_CPU1_SB_DQ<0>
  VSS44  = GND
  DQ1_B  = M_D_CPU1_SB_DQ<1>
  VSS45  = GND
  DQS0_B_T  = M_D_CPU1_SB_DQS_DP<0>
  DQS0_B_C  = M_D_CPU1_SB_DQS_DN<0>
  VSS46  = GND
  DQ4_B  = M_D_CPU1_SB_DQ<4>
  VSS47  = GND
  DQ5_B  = M_D_CPU1_SB_DQ<5>
  VSS48  = GND
  DQ8_B  = M_D_CPU1_SB_DQ<8>
  VSS49  = GND
  DQ9_B  = M_D_CPU1_SB_DQ<9>
  VSS50  = GND
  DQS1_B_T  = M_D_CPU1_SB_DQS_DP<1>
  DQS1_B_C  = M_D_CPU1_SB_DQS_DN<1>
  VSS51  = GND
  DQ12_B  = M_D_CPU1_SB_DQ<12>
  VSS52  = GND
  DQ13_B  = M_D_CPU1_SB_DQ<13>
  VSS53  = GND
  DQ16_B  = M_D_CPU1_SB_DQ<16>
  VSS54  = GND
  DQ17_B  = M_D_CPU1_SB_DQ<17>
  VSS55  = GND
  DQS2_B_T  = M_D_CPU1_SB_DQS_DP<2>
  DQS2_B_C  = M_D_CPU1_SB_DQS_DN<2>
  VSS56  = GND
  DQ20_B  = M_D_CPU1_SB_DQ<20>
  VSS57  = GND
  DQ21_B  = M_D_CPU1_SB_DQ<21>
  VSS58  = GND
  DQ24_B  = M_D_CPU1_SB_DQ<24>
  VSS59  = GND
  DQ25_B  = M_D_CPU1_SB_DQ<25>
  VSS60  = GND
  DQS3_B_T  = M_D_CPU1_SB_DQS_DP<3>
  DQS3_B_C  = M_D_CPU1_SB_DQS_DN<3>
  VSS61  = GND
  DQ28_B  = M_D_CPU1_SB_DQ<28>
  VSS62  = GND
  DQ29_B  = M_D_CPU1_SB_DQ<29>
  VSS63  = GND
  RFU1  = NC
  VIN_BULK1  = P12V_MEM_CPU1
  VIN_BULK2  = P12V_MEM_CPU1
  \pwr_good||fail_n\  = PWRGD_CHD_CPU1_DIMM
  HAS  = PD_CHD_CPU1_DIMM_SAA
  RFU2  = NC
  RFU3  = NC
  VSS64  = GND
  DQ2_A  = M_D_CPU1_SA_DQ<2>
  VSS65  = GND
  DQ3_A  = M_D_CPU1_SA_DQ<3>
  VSS66  = GND
  \dqs5_a_c||tdqs5_a_c||dqs5_a_t||tdqs5_a_t\  = M_D_CPU1_SA_DQS_DN<5>
  \dqs5_a_t||tdqs5_a_t\  = M_D_CPU1_SA_DQS_DP<5>
  VSS67  = GND
  DQ6_A  = M_D_CPU1_SA_DQ<6>
  VSS68  = GND
  DQ7_A  = M_D_CPU1_SA_DQ<7>
  VSS69  = GND
  DQ10_A  = M_D_CPU1_SA_DQ<10>
  VSS70  = GND
  DQ11_A  = M_D_CPU1_SA_DQ<11>
  VSS71  = GND
  \dqs6_a_c||tdqs6_a_c||dqs6_a_t||tdqs6_a_t\  = M_D_CPU1_SA_DQS_DN<6>
  \dqs6_a_t||tdqs6_a_t\  = M_D_CPU1_SA_DQS_DP<6>
  VSS72  = GND
  DQ14_A  = M_D_CPU1_SA_DQ<14>
  VSS73  = GND
  DQ15_A  = M_D_CPU1_SA_DQ<15>
  VSS74  = GND
  DQ18_A  = M_D_CPU1_SA_DQ<18>
  VSS75  = GND
  DQ19_A  = M_D_CPU1_SA_DQ<19>
  VSS76  = GND
  \dqs7_a_c||tdqs7_a_c\  = M_D_CPU1_SA_DQS_DN<7>
  \dqs7_a_t||tdqs7_a_t\  = M_D_CPU1_SA_DQS_DP<7>
  VSS77  = GND
  DQ22_A  = M_D_CPU1_SA_DQ<22>
  VSS78  = GND
  DQ23_A  = M_D_CPU1_SA_DQ<23>
  VSS79  = GND
  DQ26_A  = M_D_CPU1_SA_DQ<26>
  VSS80  = GND
  DQ27_A  = M_D_CPU1_SA_DQ<27>
  VSS81  = GND
  \dqs8_a_c||tdqs8_a_c\  = M_D_CPU1_SA_DQS_DN<8>
  \dqs8_a_t||tdqs8_a_t\  = M_D_CPU1_SA_DQS_DP<8>
  VSS82  = GND
  DQ30_A  = M_D_CPU1_SA_DQ<30>
  VSS83  = GND
  DQ31_A  = M_D_CPU1_SA_DQ<31>
  VSS84  = GND
  CB2_A  = M_D_CPU1_SA_CB<2>
  VSS85  = GND
  CB3_A  = M_D_CPU1_SA_CB<3>
  VSS86  = GND
  \dqs9_a_c||tdqs9_a_c\  = M_D_CPU1_SA_DQS_DN<9>
  \dqs9_a_t||tdqs9_a_t\  = M_D_CPU1_SA_DQS_DP<9>
  VSS87  = GND
  CB6_A  = M_D_CPU1_SA_CB<6>
  VSS88  = GND
  CB7_A  = M_D_CPU1_SA_CB<7>
  VSS89  = GND
  RESET_N  = M_D_CPU1_RESET_N
  VSS90  = GND
  CS1_A_N  = M_D_CPU1_SA_CS_N<1>
  VSS91  = GND
  CA1_A  = M_D_CPU1_SA_CA<1>
  VSS92  = GND
  CA3_A  = M_D_CPU1_SA_CA<3>
  VSS93  = GND
  CA5_A  = M_D_CPU1_SA_CA<5>
  VSS94  = GND
  CK_T  = M_D_CPU1_CLK_DP<0>
  CK_C  = M_D_CPU1_CLK_DN<0>
  VSS95  = GND
  RFU4  = NC
  CA1_B  = M_D_CPU1_SB_CA<1>
  VSS96  = GND
  CA3_B  = M_D_CPU1_SB_CA<3>
  VSS97  = GND
  CA5_B  = M_D_CPU1_SB_CA<5>
  VSS98  = GND
  PAR_B  = M_D_CPU1_SB_PAR
  VSS99  = GND
  CS1_B_N  = M_D_CPU1_SB_CS_N<1>
  VSS100  = GND
  RFU5  = NC
  RFU6  = NC
  VSS101  = GND
  CB6_B  = M_D_CPU1_SB_CB<6>
  VSS102  = GND
  CB7_B  = M_D_CPU1_SB_CB<7>
  VSS103  = GND
  DQS4_B_C  = M_D_CPU1_SB_DQS_DN<4>
  DQS4_B_T  = M_D_CPU1_SB_DQS_DP<4>
  VSS104  = GND
  CB2_B  = M_D_CPU1_SB_CB<2>
  VSS105  = GND
  CB3_B  = M_D_CPU1_SB_CB<3>
  VSS106  = GND
  DQ2_B  = M_D_CPU1_SB_DQ<2>
  VSS107  = GND
  DQ3_B  = M_D_CPU1_SB_DQ<3>
  VSS108  = GND
  \dqs5_b_c||tdqs5_b_c\  = M_D_CPU1_SB_DQS_DN<5>
  \dqs5_b_t||tdqs5_b_t\  = M_D_CPU1_SB_DQS_DP<5>
  VSS109  = GND
  DQ6_B  = M_D_CPU1_SB_DQ<6>
  VSS110  = GND
  DQ7_B  = M_D_CPU1_SB_DQ<7>
  VSS111  = GND
  DQ10_B  = M_D_CPU1_SB_DQ<10>
  VSS112  = GND
  DQ11_B  = M_D_CPU1_SB_DQ<11>
  VSS113  = GND
  \dqs6_b_c||tdqs6_b_c\  = M_D_CPU1_SB_DQS_DN<6>
  \dqs6_b_t||tdqs6_b_t\  = M_D_CPU1_SB_DQS_DP<6>
  VSS114  = GND
  DQ14_B  = M_D_CPU1_SB_DQ<14>
  VSS115  = GND
  DQ15_B  = M_D_CPU1_SB_DQ<15>
  VSS116  = GND
  DQ18_B  = M_D_CPU1_SB_DQ<18>
  VSS117  = GND
  DQ19_B  = M_D_CPU1_SB_DQ<19>
  VSS118  = GND
  \dqs7_b_c||tdqs7_b_c\  = M_D_CPU1_SB_DQS_DN<7>
  \dqs7_b_t||tdqs7_b_t\  = M_D_CPU1_SB_DQS_DP<7>
  VSS119  = GND
  DQ22_B  = M_D_CPU1_SB_DQ<22>
  VSS120  = GND
  DQ23_B  = M_D_CPU1_SB_DQ<23>
  VSS121  = GND
  DQ26_B  = M_D_CPU1_SB_DQ<26>
  VSS122  = GND
  DQ27_B  = M_D_CPU1_SB_DQ<27>
  VSS123  = GND
  \dqs8_b_c||tdqs8_b_c\  = M_D_CPU1_SB_DQS_DN<8>
  \dqs8_b_t||tdqs8_b_t\  = M_D_CPU1_SB_DQS_DP<8>
  VSS124  = GND
  DQ30_B  = M_D_CPU1_SB_DQ<30>
  VSS125  = GND
  DQ31_B  = M_D_CPU1_SB_DQ<31>
  VSS126  = GND
  G1  = GND
  G2  = GND
  G3  = GND

(kicad_pcb
	(version 20260206)
	(generator "pcbnew")
	(generator_version "10.0")
	(general
		(thickness 1.6)
		(legacy_teardrops no)
	)
	(paper "A4")
	(title_block
		(title "04192023_DAF0TMB3IC0_F0TG_MB_C_brd_V02_OCP.brd")
		(comment 1 "Grand Teton / footprint 3579 of 8354 (J30), pads 47-92 of 291")
	)
	(layers
		(0 "F.Cu" signal "TOP")
		(4 "In1.Cu" signal "GND")
		(6 "In2.Cu" signal "IN1")
		(8 "In3.Cu" signal "GND1")
		(10 "In4.Cu" signal "IN2")
		(12 "In5.Cu" signal "GND2")
		(14 "In6.Cu" signal "IN3")
		(16 "In7.Cu" signal "GND3")
		(18 "In8.Cu" signal "VCC")
		(20 "In9.Cu" signal "VCC1")
		(22 "In10.Cu" signal "GND4")
		(24 "In11.Cu" signal "IN4")
		(26 "In12.Cu" signal "GND5")
		(28 "In13.Cu" signal "IN5")
		(30 "In14.Cu" signal "GND6")
		(32 "In15.Cu" signal "IN6")
		(34 "In16.Cu" signal "GND7")
		(2 "B.Cu" signal "BOTTOM")
		(9 "F.Adhes" user "F.Adhesive")
		(11 "B.Adhes" user "B.Adhesive")
		(13 "F.Paste" user "Package Geometry/Pastemask Top")
		(15 "B.Paste" user "Package Geometry/Pastemask Bottom")
		(5 "F.SilkS" user "Ref Des/Silkscreen Top")
		(7 "B.SilkS" user "Ref Des/Silkscreen Bottom")
		(1 "F.Mask" user "Board Geometry/Soldermask Top")
		(3 "B.Mask" user "Board Geometry/Soldermask Bottom")
		(17 "Dwgs.User" user "User.Drawings")
		(19 "Cmts.User" user "User.Comments")
		(21 "Eco1.User" user "User.Eco1")
		(23 "Eco2.User" user "User.Eco2")
		(25 "Edge.Cuts" user "Board Geometry/Outline")
		(27 "Margin" user)
		(31 "F.CrtYd" user "Package Geometry/Place Bound Top")
		(29 "B.CrtYd" user "Package Geometry/Place Bound Bottom")
		(35 "F.Fab" user "Ref Des/Assembly Top")
		(33 "B.Fab" user "Ref Des/Assembly Bottom")
	)
	(footprint ""
		(layer "F.Cu")
		(at 34.74593 -255.560322 180)
		(property "Reference" "J30"
			(at 3.12293 -81.850992 0)
			(unlocked yes)
			(layer "F.SilkS")
			(effects
				(font
					(size 0.7874 0.5842)
					(thickness 0.1524)
				)
			)
		)
		(property "Value" ""
			(at 0 0 180)
			(layer "F.Fab")
			(effects
				(font
					(size 1.27 1.27)
				)
			)
		)
		(duplicate_pad_numbers_are_jumpers no)
		(pad "47" smd rect
			(at -2.050034 -24.224996 90)
			(size 0.519938 1.4986)
			(layers "F.Cu" "F.Mask" "F.Paste")
			(net "M_D_CPU1_SA_DQ<28>")
		)
		(pad "48" smd rect
			(at -2.050034 -23.375112 90)
			(size 0.519938 1.4986)
			(layers "F.Cu" "F.Mask" "F.Paste")
			(net "GND")
		)
		(pad "49" smd rect
			(at -2.050034 -22.524974 90)
			(size 0.519938 1.4986)
			(layers "F.Cu" "F.Mask" "F.Paste")
			(net "M_D_CPU1_SA_DQ<29>")
		)
		(pad "50" smd rect
			(at -2.050034 -21.67509 90)
			(size 0.519938 1.4986)
			(layers "F.Cu" "F.Mask" "F.Paste")
			(net "GND")
		)
		(pad "51" smd rect
			(at -2.050034 -20.824952 90)
			(size 0.519938 1.4986)
			(layers "F.Cu" "F.Mask" "F.Paste")
			(net "M_D_CPU1_SA_CB<0>")
		)
		(pad "52" smd rect
			(at -2.050034 -19.975068 90)
			(size 0.519938 1.4986)
			(layers "F.Cu" "F.Mask" "F.Paste")
			(net "GND")
		)
		(pad "53" smd rect
			(at -2.050034 -19.12493 90)
			(size 0.519938 1.4986)
			(layers "F.Cu" "F.Mask" "F.Paste")
			(net "M_D_CPU1_SA_CB<1>")
		)
		(pad "54" smd rect
			(at -2.050034 -18.275046 90)
			(size 0.519938 1.4986)
			(layers "F.Cu" "F.Mask" "F.Paste")
			(net "GND")
		)
		(pad "55" smd rect
			(at -2.050034 -17.424908 90)
			(size 0.519938 1.4986)
			(layers "F.Cu" "F.Mask" "F.Paste")
			(net "M_D_CPU1_SA_DQS_DP<4>")
		)
		(pad "56" smd rect
			(at -2.050034 -16.575024 90)
			(size 0.519938 1.4986)
			(layers "F.Cu" "F.Mask" "F.Paste")
			(net "M_D_CPU1_SA_DQS_DN<4>")
		)
		(pad "57" smd rect
			(at -2.050034 -15.724886 90)
			(size 0.519938 1.4986)
			(layers "F.Cu" "F.Mask" "F.Paste")
			(net "GND")
		)
		(pad "58" smd rect
			(at -2.050034 -14.875002 90)
			(size 0.519938 1.4986)
			(layers "F.Cu" "F.Mask" "F.Paste")
			(net "M_D_CPU1_SA_CB<4>")
		)
		(pad "59" smd rect
			(at -2.050034 -14.025118 90)
			(size 0.519938 1.4986)
			(layers "F.Cu" "F.Mask" "F.Paste")
			(net "GND")
		)
		(pad "60" smd rect
			(at -2.050034 -13.17498 90)
			(size 0.519938 1.4986)
			(layers "F.Cu" "F.Mask" "F.Paste")
			(net "M_D_CPU1_SA_CB<5>")
		)
		(pad "61" smd rect
			(at -2.050034 -12.325096 90)
			(size 0.519938 1.4986)
			(layers "F.Cu" "F.Mask" "F.Paste")
			(net "GND")
		)
		(pad "62" smd rect
			(at -2.050034 -11.474958 90)
			(size 0.519938 1.4986)
			(layers "F.Cu" "F.Mask" "F.Paste")
			(net "M_D_CPU1_ALERT_N")
		)
		(pad "63" smd rect
			(at -2.050034 -10.625074 90)
			(size 0.519938 1.4986)
			(layers "F.Cu" "F.Mask" "F.Paste")
			(net "GND")
		)
		(pad "64" smd rect
			(at -2.050034 -9.774936 90)
			(size 0.519938 1.4986)
			(layers "F.Cu" "F.Mask" "F.Paste")
			(net "M_D_CPU1_SA_CS_N<0>")
		)
		(pad "65" smd rect
			(at -2.050034 -8.925052 90)
			(size 0.519938 1.4986)
			(layers "F.Cu" "F.Mask" "F.Paste")
			(net "GND")
		)
		(pad "66" smd rect
			(at -2.050034 -8.074914 90)
			(size 0.519938 1.4986)
			(layers "F.Cu" "F.Mask" "F.Paste")
			(net "M_D_CPU1_SA_CA<0>")
		)
		(pad "67" smd rect
			(at -2.050034 -7.22503 90)
			(size 0.519938 1.4986)
			(layers "F.Cu" "F.Mask" "F.Paste")
			(net "GND")
		)
		(pad "68" smd rect
			(at -2.050034 -6.374892 90)
			(size 0.519938 1.4986)
			(layers "F.Cu" "F.Mask" "F.Paste")
			(net "M_D_CPU1_SA_CA<2>")
		)
		(pad "69" smd rect
			(at -2.050034 -5.525008 90)
			(size 0.519938 1.4986)
			(layers "F.Cu" "F.Mask" "F.Paste")
			(net "GND")
		)
		(pad "70" smd rect
			(at -2.050034 -4.675124 90)
			(size 0.519938 1.4986)
			(layers "F.Cu" "F.Mask" "F.Paste")
			(net "M_D_CPU1_SA_CA<4>")
		)
		(pad "71" smd rect
			(at -2.050034 -3.824986 90)
			(size 0.519938 1.4986)
			(layers "F.Cu" "F.Mask" "F.Paste")
			(net "GND")
		)
		(pad "72" smd rect
			(at -2.050034 -2.975102 90)
			(size 0.519938 1.4986)
			(layers "F.Cu" "F.Mask" "F.Paste")
			(net "M_D_CPU1_SA_CA<6>")
		)
		(pad "73" smd rect
			(at -2.050034 -2.124964 90)
			(size 0.519938 1.4986)
			(layers "F.Cu" "F.Mask" "F.Paste")
			(net "GND")
		)
		(pad "74" smd rect
			(at -2.050034 -1.27508 90)
			(size 0.519938 1.4986)
			(layers "F.Cu" "F.Mask" "F.Paste")
			(net "M_D_CPU1_SA_PAR")
		)
		(pad "75" smd rect
			(at -2.050034 -0.424942 90)
			(size 0.519938 1.4986)
			(layers "F.Cu" "F.Mask" "F.Paste")
			(net "GND")
		)
		(pad "76" smd rect
			(at -2.050034 5.525008 90)
			(size 0.519938 1.4986)
			(layers "F.Cu" "F.Mask" "F.Paste")
			(net "M_D_CPU1_SB_CA<0>")
		)
		(pad "77" smd rect
			(at -2.050034 6.374892 90)
			(size 0.519938 1.4986)
			(layers "F.Cu" "F.Mask" "F.Paste")
			(net "GND")
		)
		(pad "78" smd rect
			(at -2.050034 7.22503 90)
			(size 0.519938 1.4986)
			(layers "F.Cu" "F.Mask" "F.Paste")
			(net "M_D_CPU1_SB_CA<2>")
		)
		(pad "79" smd rect
			(at -2.050034 8.074914 90)
			(size 0.519938 1.4986)
			(layers "F.Cu" "F.Mask" "F.Paste")
			(net "GND")
		)
		(pad "80" smd rect
			(at -2.050034 8.925052 90)
			(size 0.519938 1.4986)
			(layers "F.Cu" "F.Mask" "F.Paste")
			(net "M_D_CPU1_SB_CA<4>")
		)
		(pad "81" smd rect
			(at -2.050034 9.774936 90)
			(size 0.519938 1.4986)
			(layers "F.Cu" "F.Mask" "F.Paste")
			(net "GND")
		)
		(pad "82" smd rect
			(at -2.050034 10.625074 90)
			(size 0.519938 1.4986)
			(layers "F.Cu" "F.Mask" "F.Paste")
			(net "M_D_CPU1_SB_CA<6>")
		)
		(pad "83" smd rect
			(at -2.050034 11.474958 90)
			(size 0.519938 1.4986)
			(layers "F.Cu" "F.Mask" "F.Paste")
			(net "GND")
		)
		(pad "84" smd rect
			(at -2.050034 12.325096 90)
			(size 0.519938 1.4986)
			(layers "F.Cu" "F.Mask" "F.Paste")
			(net "M_D_CPU1_SB_CS_N<0>")
		)
		(pad "85" smd rect
			(at -2.050034 13.17498 90)
			(size 0.519938 1.4986)
			(layers "F.Cu" "F.Mask" "F.Paste")
			(net "GND")
		)
		(pad "86" smd rect
			(at -2.050034 14.025118 90)
			(size 0.519938 1.4986)
			(layers "F.Cu" "F.Mask" "F.Paste")
			(net "M_D_CPU1_SA_RSP<0>")
		)
		(pad "87" smd rect
			(at -2.050034 14.875002 90)
			(size 0.519938 1.4986)
			(layers "F.Cu" "F.Mask" "F.Paste")
			(net "M_D_CPU1_SB_RSP<0>")
		)
		(pad "88" smd rect
			(at -2.050034 15.724886 90)
			(size 0.519938 1.4986)
			(layers "F.Cu" "F.Mask" "F.Paste")
			(net "GND")
		)
		(pad "89" smd rect
			(at -2.050034 16.575024 90)
			(size 0.519938 1.4986)
			(layers "F.Cu" "F.Mask" "F.Paste")
			(net "M_D_CPU1_SB_CB<4>")
		)
		(pad "90" smd rect
			(at -2.050034 17.424908 90)
			(size 0.519938 1.4986)
			(layers "F.Cu" "F.Mask" "F.Paste")
			(net "GND")
		)
		(pad "91" smd rect
			(at -2.050034 18.275046 90)
			(size 0.519938 1.4986)
			(layers "F.Cu" "F.Mask" "F.Paste")
			(net "M_D_CPU1_SB_CB<5>")
		)
		(pad "92" smd rect
			(at -2.050034 19.12493 90)
			(size 0.519938 1.4986)
			(layers "F.Cu" "F.Mask" "F.Paste")
			(net "GND")
		)
	)
)
